# T6G (Grand Teton) — schematic netlist excerpt (pin names and nets, part order shuffled) for the footprints in the layout excerpt that follows; sources: Cadence DE-HDL packaged netlist, KiCad conversion of 04192023_DAF0TMB3IC0_F0TG_MB_C_brd_V02_OCP.brd

R3529  Q_RES  10K 1% CHIP  pkg 0402LF  page 148 : A = P3V3_AUX ; B = SMB_PCIE_E1S_ISO_EN_R
R4066  Q_RES  4.7K 5% EMPTY  pkg 0402LF  page 140 : A = P3V3_OCP_EN_2_R ; B = GND

(kicad_pcb
	(version 20260206)
	(generator "pcbnew")
	(generator_version "10.0")
	(general
		(thickness 1.6)
		(legacy_teardrops no)
	)
	(paper "A4")
	(title_block
		(title "04192023_DAF0TMB3IC0_F0TG_MB_C_brd_V02_OCP.brd")
		(comment 1 "Grand Teton / footprints 1-2 of 8354")
	)
	(layers
		(0 "F.Cu" signal "TOP")
		(4 "In1.Cu" signal "GND")
		(6 "In2.Cu" signal "IN1")
		(8 "In3.Cu" signal "GND1")
		(10 "In4.Cu" signal "IN2")
		(12 "In5.Cu" signal "GND2")
		(14 "In6.Cu" signal "IN3")
		(16 "In7.Cu" signal "GND3")
		(18 "In8.Cu" signal "VCC")
		(20 "In9.Cu" signal "VCC1")
		(22 "In10.Cu" signal "GND4")
		(24 "In11.Cu" signal "IN4")
		(26 "In12.Cu" signal "GND5")
		(28 "In13.Cu" signal "IN5")
		(30 "In14.Cu" signal "GND6")
		(32 "In15.Cu" signal "IN6")
		(34 "In16.Cu" signal "GND7")
		(2 "B.Cu" signal "BOTTOM")
		(9 "F.Adhes" user "F.Adhesive")
		(11 "B.Adhes" user "B.Adhesive")
		(13 "F.Paste" user "Package Geometry/Pastemask Top")
		(15 "B.Paste" user "Package Geometry/Pastemask Bottom")
		(5 "F.SilkS" user "Ref Des/Silkscreen Top")
		(7 "B.SilkS" user "Ref Des/Silkscreen Bottom")
		(1 "F.Mask" user "Board Geometry/Soldermask Top")
		(3 "B.Mask" user "Board Geometry/Soldermask Bottom")
		(17 "Dwgs.User" user "User.Drawings")
		(19 "Cmts.User" user "User.Comments")
		(21 "Eco1.User" user "User.Eco1")
		(23 "Eco2.User" user "User.Eco2")
		(25 "Edge.Cuts" user "Board Geometry/Outline")
		(27 "Margin" user)
		(31 "F.CrtYd" user "Package Geometry/Place Bound Top")
		(29 "B.CrtYd" user "Package Geometry/Place Bound Bottom")
		(35 "F.Fab" user "Ref Des/Assembly Top")
		(33 "B.Fab" user "Ref Des/Assembly Bottom")
	)
	(footprint ""
		(layer "F.Cu")
		(at 210.74888 -42.382948)
		(property "Reference" "R3529"
			(at 0 0 0)
			(layer "F.SilkS")
			(hide yes)
			(effects
				(font
					(size 1.27 1.27)
				)
			)
		)
		(property "Value" ""
			(at 0 0 0)
			(layer "F.Fab")
			(effects
				(font
					(size 1.27 1.27)
				)
			)
		)
		(duplicate_pad_numbers_are_jumpers no)
		(fp_line
			(start -0.7874 -0.4064)
			(end 0.7874 -0.4064)
			(stroke
				(width 0.1524)
				(type default)
			)
			(layer "F.SilkS")
		)
		(fp_line
			(start -0.7874 0.4064)
			(end -0.7874 -0.4064)
			(stroke
				(width 0.1524)
				(type default)
			)
			(layer "F.SilkS")
		)
		(fp_line
			(start 0.7874 -0.4064)
			(end 0.7874 0.4064)
			(stroke
				(width 0.1524)
				(type default)
			)
			(layer "F.SilkS")
		)
		(fp_line
			(start 0.7874 0.4064)
			(end -0.7874 0.4064)
			(stroke
				(width 0.1524)
				(type default)
			)
			(layer "F.SilkS")
		)
		(fp_line
			(start -0.67945 -0.305054)
			(end -0.12065 -0.305054)
			(stroke
				(width 0.1)
				(type default)
			)
			(layer "F.Fab")
		)
		(fp_line
			(start -0.67945 0.3048)
			(end -0.67945 -0.305054)
			(stroke
				(width 0.1)
				(type default)
			)
			(layer "F.Fab")
		)
		(fp_line
			(start -0.12065 -0.305054)
			(end -0.12065 -0.2794)
			(stroke
				(width 0.1)
				(type default)
			)
			(layer "F.Fab")
		)
		(fp_line
			(start -0.12065 -0.2794)
			(end 0.12065 -0.2794)
			(stroke
				(width 0.1)
				(type default)
			)
			(layer "F.Fab")
		)
		(fp_line
			(start -0.12065 0.2794)
			(end -0.12065 0.3048)
			(stroke
				(width 0.1)
				(type default)
			)
			(layer "F.Fab")
		)
		(fp_line
			(start -0.12065 0.3048)
			(end -0.67945 0.3048)
			(stroke
				(width 0.1)
				(type default)
			)
			(layer "F.Fab")
		)
		(fp_line
			(start 0.120396 0.2794)
			(end -0.12065 0.2794)
			(stroke
				(width 0.1)
				(type default)
			)
			(layer "F.Fab")
		)
		(fp_line
			(start 0.120396 0.3048)
			(end 0.120396 0.2794)
			(stroke
				(width 0.1)
				(type default)
			)
			(layer "F.Fab")
		)
		(fp_line
			(start 0.12065 -0.3048)
			(end 0.67945 -0.3048)
			(stroke
				(width 0.1)
				(type default)
			)
			(layer "F.Fab")
		)
		(fp_line
			(start 0.12065 -0.2794)
			(end 0.12065 -0.3048)
			(stroke
				(width 0.1)
				(type default)
			)
			(layer "F.Fab")
		)
		(fp_line
			(start 0.67945 -0.3048)
			(end 0.67945 0.3048)
			(stroke
				(width 0.1)
				(type default)
			)
			(layer "F.Fab")
		)
		(fp_line
			(start 0.67945 0.3048)
			(end 0.120396 0.3048)
			(stroke
				(width 0.1)
				(type default)
			)
			(layer "F.Fab")
		)
		(pad "1" smd circle
			(at -0.40005 0)
			(size 0 0)
			(layers "F.Cu" "F.Mask" "F.Paste")
			(net "P3V3_AUX")
		)
		(pad "2" smd circle
			(at 0.40005 0)
			(size 0 0)
			(layers "F.Cu" "F.Mask" "F.Paste")
			(net "SMB_PCIE_E1S_ISO_EN_R")
		)
	)
	(footprint ""
		(layer "F.Cu")
		(at 58.93308 -40.404034 180)
		(property "Reference" "R4066"
			(at 0 0 180)
			(layer "F.SilkS")
			(hide yes)
			(effects
				(font
					(size 1.27 1.27)
				)
			)
		)
		(property "Value" ""
			(at 0 0 180)
			(layer "F.Fab")
			(effects
				(font
					(size 1.27 1.27)
				)
			)
		)
		(duplicate_pad_numbers_are_jumpers no)
		(fp_line
			(start 0.7874 0.4064)
			(end -0.7874 0.4064)
			(stroke
				(width 0.1524)
				(type default)
			)
			(layer "F.SilkS")
		)
		(fp_line
			(start 0.7874 -0.4064)
			(end 0.7874 0.4064)
			(stroke
				(width 0.1524)
				(type default)
			)
			(layer "F.SilkS")
		)
		(fp_line
			(start -0.7874 0.4064)
			(end -0.7874 -0.4064)
			(stroke
				(width 0.1524)
				(type default)
			)
			(layer "F.SilkS")
		)
		(fp_line
			(start -0.7874 -0.4064)
			(end 0.7874 -0.4064)
			(stroke
				(width 0.1524)
				(type default)
			)
			(layer "F.SilkS")
		)
		(fp_line
			(start 0.67945 0.3048)
			(end 0.120396 0.3048)
			(stroke
				(width 0.1)
				(type default)
			)
			(layer "F.Fab")
		)
		(fp_line
			(start 0.67945 -0.3048)
			(end 0.67945 0.3048)
			(stroke
				(width 0.1)
				(type default)
			)
			(layer "F.Fab")
		)
		(fp_line
			(start 0.12065 -0.2794)
			(end 0.12065 -0.3048)
			(stroke
				(width 0.1)
				(type default)
			)
			(layer "F.Fab")
		)
		(fp_line
			(start 0.12065 -0.3048)
			(end 0.67945 -0.3048)
			(stroke
				(width 0.1)
				(type default)
			)
			(layer "F.Fab")
		)
		(fp_line
			(start 0.120396 0.3048)
			(end 0.120396 0.2794)
			(stroke
				(width 0.1)
				(type default)
			)
			(layer "F.Fab")
		)
		(fp_line
			(start 0.120396 0.2794)
			(end -0.12065 0.2794)
			(stroke
				(width 0.1)
				(type default)
			)
			(layer "F.Fab")
		)
		(fp_line
			(start -0.12065 0.3048)
			(end -0.67945 0.3048)
			(stroke
				(width 0.1)
				(type default)
			)
			(layer "F.Fab")
		)
		(fp_line
			(start -0.12065 0.2794)
			(end -0.12065 0.3048)
			(stroke
				(width 0.1)
				(type default)
			)
			(layer "F.Fab")
		)
		(fp_line
			(start -0.12065 -0.2794)
			(end 0.12065 -0.2794)
			(stroke
				(width 0.1)
				(type default)
			)
			(layer "F.Fab")
		)
		(fp_line
			(start -0.12065 -0.305054)
			(end -0.12065 -0.2794)
			(stroke
				(width 0.1)
				(type default)
			)
			(layer "F.Fab")
		)
		(fp_line
			(start -0.67945 0.3048)
			(end -0.67945 -0.305054)
			(stroke
				(width 0.1)
				(type default)
			)
			(layer "F.Fab")
		)
		(fp_line
			(start -0.67945 -0.305054)
			(end -0.12065 -0.305054)
			(stroke
				(width 0.1)
				(type default)
			)
			(layer "F.Fab")
		)
		(pad "1" smd circle
			(at -0.40005 0 180)
			(size 0 0)
			(layers "F.Cu" "F.Mask" "F.Paste")
			(net "P3V3_OCP_EN_2_R")
		)
		(pad "2" smd circle
			(at 0.40005 0 180)
			(size 0 0)
			(layers "F.Cu" "F.Mask" "F.Paste")
			(net "GND")
		)
	)
)
